(kicad_pcb
	(version 20260206)
	(generator "pcbnew")
	(generator_version "10.0")
	(general
		(thickness 1.6)
		(legacy_teardrops no)
	)
	(paper "A4")
	(title_block
		(title "01162023_DA0F0TEBIF0_F0T_Expander_BD_F_brd_V02_OCP.brd")
		(comment 1 "Grand Teton / footprint 6602 of 9728 (PEX1), pads 1537-1653 of 2397")
	)
	(layers
		(0 "F.Cu" signal "TOP")
		(4 "In1.Cu" signal "GND")
		(6 "In2.Cu" signal "VCC")
		(8 "In3.Cu" signal "VCC1")
		(10 "In4.Cu" signal "GND1")
		(12 "In5.Cu" signal "IN1")
		(14 "In6.Cu" signal "GND2")
		(16 "In7.Cu" signal "IN2")
		(18 "In8.Cu" signal "GND3")
		(20 "In9.Cu" signal "IN3")
		(22 "In10.Cu" signal "GND4")
		(24 "In11.Cu" signal "IN4")
		(26 "In12.Cu" signal "GND5")
		(28 "In13.Cu" signal "IN5")
		(30 "In14.Cu" signal "GND6")
		(32 "In15.Cu" signal "IN6")
		(34 "In16.Cu" signal "GND7")
		(2 "B.Cu" signal "BOTTOM")
		(9 "F.Adhes" user "F.Adhesive")
		(11 "B.Adhes" user "B.Adhesive")
		(13 "F.Paste" user "Package Geometry/Pastemask Top")
		(15 "B.Paste" user "Package Geometry/Pastemask Bottom")
		(5 "F.SilkS" user "Ref Des/Silkscreen Top")
		(7 "B.SilkS" user "Ref Des/Silkscreen Bottom")
		(1 "F.Mask" user "Board Geometry/Soldermask Top")
		(3 "B.Mask" user "Board Geometry/Soldermask Bottom")
		(17 "Dwgs.User" user "User.Drawings")
		(19 "Cmts.User" user "User.Comments")
		(21 "Eco1.User" user "User.Eco1")
		(23 "Eco2.User" user "User.Eco2")
		(25 "Edge.Cuts" user "Board Geometry/Outline")
		(27 "Margin" user)
		(31 "F.CrtYd" user "Package Geometry/Place Bound Top")
		(29 "B.CrtYd" user "Package Geometry/Place Bound Bottom")
		(35 "F.Fab" user "Ref Des/Assembly Top")
		(33 "B.Fab" user "Ref Des/Assembly Bottom")
	)
	(footprint ""
		(layer "F.Cu")
		(at 175.749966 -295.89984)
		(property "Reference" "PEX1"
			(at -3.353562 35.593274 0)
			(unlocked yes)
			(layer "F.SilkS")
			(effects
				(font
					(size 2.032 1.524)
					(thickness 0.1524)
				)
				(justify left)
			)
		)
		(property "Value" ""
			(at 0 0 0)
			(layer "F.Fab")
			(effects
				(font
					(size 1.27 1.27)
				)
			)
		)
		(duplicate_pad_numbers_are_jumpers no)
		(pad "C22" smd circle
			(at -2.84988 -20.899882)
			(size 0.4572 0.4572)
			(layers "F.Cu" "F.Mask" "F.Paste")
			(net "P5E_PEX1_STN6_RX_DN<97>")
		)
		(pad "C23" smd circle
			(at -1.89992 -20.899882)
			(size 0.4572 0.4572)
			(layers "F.Cu" "F.Mask" "F.Paste")
			(net "GND")
		)
		(pad "C24" smd circle
			(at -0.94996 -20.899882)
			(size 0.4572 0.4572)
			(layers "F.Cu" "F.Mask" "F.Paste")
			(net "P5E_PEX1_STN5_RX_DN<80>")
		)
		(pad "C25" smd circle
			(at 0 -20.899882)
			(size 0.4572 0.4572)
			(layers "F.Cu" "F.Mask" "F.Paste")
			(net "GND")
		)
		(pad "C26" smd circle
			(at 0.94996 -20.899882)
			(size 0.4572 0.4572)
			(layers "F.Cu" "F.Mask" "F.Paste")
			(net "P5E_PEX1_STN5_RX_DN<82>")
		)
		(pad "C27" smd circle
			(at 1.89992 -20.899882)
			(size 0.4572 0.4572)
			(layers "F.Cu" "F.Mask" "F.Paste")
			(net "GND")
		)
		(pad "C28" smd circle
			(at 2.84988 -20.899882)
			(size 0.4572 0.4572)
			(layers "F.Cu" "F.Mask" "F.Paste")
			(net "P5E_PEX1_STN5_RX_DN<84>")
		)
		(pad "C29" smd circle
			(at 3.800094 -20.899882)
			(size 0.4572 0.4572)
			(layers "F.Cu" "F.Mask" "F.Paste")
			(net "GND")
		)
		(pad "C30" smd circle
			(at 4.750054 -20.899882)
			(size 0.4572 0.4572)
			(layers "F.Cu" "F.Mask" "F.Paste")
			(net "P5E_PEX1_STN5_RX_DN<86>")
		)
		(pad "C31" smd circle
			(at 5.700014 -20.899882)
			(size 0.4572 0.4572)
			(layers "F.Cu" "F.Mask" "F.Paste")
			(net "GND")
		)
		(pad "C32" smd circle
			(at 6.649974 -20.899882)
			(size 0.4572 0.4572)
			(layers "F.Cu" "F.Mask" "F.Paste")
			(net "P5E_PEX1_STN5_RX_DN<88>")
		)
		(pad "C33" smd circle
			(at 7.599934 -20.899882)
			(size 0.4572 0.4572)
			(layers "F.Cu" "F.Mask" "F.Paste")
			(net "GND")
		)
		(pad "C34" smd circle
			(at 8.549894 -20.899882)
			(size 0.4572 0.4572)
			(layers "F.Cu" "F.Mask" "F.Paste")
			(net "P5E_PEX1_STN5_RX_DN<90>")
		)
		(pad "C35" smd circle
			(at 9.500108 -20.899882)
			(size 0.4572 0.4572)
			(layers "F.Cu" "F.Mask" "F.Paste")
			(net "GND")
		)
		(pad "C36" smd circle
			(at 10.450068 -20.899882)
			(size 0.4572 0.4572)
			(layers "F.Cu" "F.Mask" "F.Paste")
			(net "P5E_PEX1_STN5_RX_DN<92>")
		)
		(pad "C37" smd circle
			(at 11.400028 -20.899882)
			(size 0.4572 0.4572)
			(layers "F.Cu" "F.Mask" "F.Paste")
			(net "GND")
		)
		(pad "C38" smd circle
			(at 12.349988 -20.899882)
			(size 0.4572 0.4572)
			(layers "F.Cu" "F.Mask" "F.Paste")
			(net "P5E_PEX1_STN5_RX_DN<94>")
		)
		(pad "C39" smd circle
			(at 13.299948 -20.899882)
			(size 0.4572 0.4572)
			(layers "F.Cu" "F.Mask" "F.Paste")
			(net "GND")
		)
		(pad "C40" smd circle
			(at 14.249908 -20.899882)
			(size 0.4572 0.4572)
			(layers "F.Cu" "F.Mask" "F.Paste")
			(net "P5E_PEX1_STN4_RX_DN<79>")
		)
		(pad "C41" smd circle
			(at 15.200122 -20.899882)
			(size 0.4572 0.4572)
			(layers "F.Cu" "F.Mask" "F.Paste")
			(net "GND")
		)
		(pad "C42" smd circle
			(at 16.150082 -20.899882)
			(size 0.4572 0.4572)
			(layers "F.Cu" "F.Mask" "F.Paste")
			(net "P5E_PEX1_STN4_RX_DN<77>")
		)
		(pad "C43" smd circle
			(at 17.100042 -20.899882)
			(size 0.4572 0.4572)
			(layers "F.Cu" "F.Mask" "F.Paste")
			(net "GND")
		)
		(pad "C44" smd circle
			(at 18.050002 -20.899882)
			(size 0.4572 0.4572)
			(layers "F.Cu" "F.Mask" "F.Paste")
			(net "P5E_PEX1_STN4_RX_DN<75>")
		)
		(pad "C45" smd circle
			(at 18.999962 -20.899882)
			(size 0.4572 0.4572)
			(layers "F.Cu" "F.Mask" "F.Paste")
			(net "GND")
		)
		(pad "C46" smd circle
			(at 19.949922 -20.899882)
			(size 0.4572 0.4572)
			(layers "F.Cu" "F.Mask" "F.Paste")
			(net "P5E_PEX1_STN4_RX_DN<73>")
		)
		(pad "C47" smd circle
			(at 20.899882 -20.899882)
			(size 0.4572 0.4572)
			(layers "F.Cu" "F.Mask" "F.Paste")
			(net "GND")
		)
		(pad "C48" smd circle
			(at 21.850096 -20.899882)
			(size 0.4572 0.4572)
			(layers "F.Cu" "F.Mask" "F.Paste")
			(net "P5E_PEX1_STN4_RX_DP<71>")
		)
		(pad "C49" smd circle
			(at 22.800056 -20.899882)
			(size 0.4572 0.4572)
			(layers "F.Cu" "F.Mask" "F.Paste")
			(net "P5E_PEX1_STN4_RX_DN<71>")
		)
		(pad "D1" smd circle
			(at -22.800056 -19.949922)
			(size 0.4572 0.4572)
			(layers "F.Cu" "F.Mask" "F.Paste")
			(net "GND")
		)
		(pad "D2" smd circle
			(at -21.850096 -19.949922)
			(size 0.4572 0.4572)
			(layers "F.Cu" "F.Mask" "F.Paste")
			(net "GND")
		)
		(pad "D3" smd circle
			(at -20.899882 -19.949922)
			(size 0.4572 0.4572)
			(layers "F.Cu" "F.Mask" "F.Paste")
			(net "GND")
		)
		(pad "D4" smd circle
			(at -19.949922 -19.949922)
			(size 0.4572 0.4572)
			(layers "F.Cu" "F.Mask" "F.Paste")
			(net "P5E_PEX1_STN7_RX_DP<124>")
		)
		(pad "D5" smd circle
			(at -18.999962 -19.949922)
			(size 0.4572 0.4572)
			(layers "F.Cu" "F.Mask" "F.Paste")
			(net "GND")
		)
		(pad "D6" smd circle
			(at -18.050002 -19.949922)
			(size 0.4572 0.4572)
			(layers "F.Cu" "F.Mask" "F.Paste")
			(net "P5E_PEX1_STN7_RX_DP<126>")
		)
		(pad "D7" smd circle
			(at -17.100042 -19.949922)
			(size 0.4572 0.4572)
			(layers "F.Cu" "F.Mask" "F.Paste")
			(net "GND")
		)
		(pad "D8" smd circle
			(at -16.150082 -19.949922)
			(size 0.4572 0.4572)
			(layers "F.Cu" "F.Mask" "F.Paste")
			(net "P5E_PEX1_STN6_RX_DP<111>")
		)
		(pad "D9" smd circle
			(at -15.200122 -19.949922)
			(size 0.4572 0.4572)
			(layers "F.Cu" "F.Mask" "F.Paste")
			(net "GND")
		)
		(pad "D10" smd circle
			(at -14.249908 -19.949922)
			(size 0.4572 0.4572)
			(layers "F.Cu" "F.Mask" "F.Paste")
			(net "P5E_PEX1_STN6_RX_DP<109>")
		)
		(pad "D11" smd circle
			(at -13.299948 -19.949922)
			(size 0.4572 0.4572)
			(layers "F.Cu" "F.Mask" "F.Paste")
			(net "GND")
		)
		(pad "D12" smd circle
			(at -12.349988 -19.949922)
			(size 0.4572 0.4572)
			(layers "F.Cu" "F.Mask" "F.Paste")
			(net "P5E_PEX1_STN6_RX_DP<107>")
		)
		(pad "D13" smd circle
			(at -11.400028 -19.949922)
			(size 0.4572 0.4572)
			(layers "F.Cu" "F.Mask" "F.Paste")
			(net "GND")
		)
		(pad "D14" smd circle
			(at -10.450068 -19.949922)
			(size 0.4572 0.4572)
			(layers "F.Cu" "F.Mask" "F.Paste")
			(net "P5E_PEX1_STN6_RX_DP<105>")
		)
		(pad "D15" smd circle
			(at -9.500108 -19.949922)
			(size 0.4572 0.4572)
			(layers "F.Cu" "F.Mask" "F.Paste")
			(net "GND")
		)
		(pad "D16" smd circle
			(at -8.549894 -19.949922)
			(size 0.4572 0.4572)
			(layers "F.Cu" "F.Mask" "F.Paste")
			(net "P5E_PEX1_STN6_RX_DP<103>")
		)
		(pad "D17" smd circle
			(at -7.599934 -19.949922)
			(size 0.4572 0.4572)
			(layers "F.Cu" "F.Mask" "F.Paste")
			(net "GND")
		)
		(pad "D18" smd circle
			(at -6.649974 -19.949922)
			(size 0.4572 0.4572)
			(layers "F.Cu" "F.Mask" "F.Paste")
			(net "P5E_PEX1_STN6_RX_DP<101>")
		)
		(pad "D19" smd circle
			(at -5.700014 -19.949922)
			(size 0.4572 0.4572)
			(layers "F.Cu" "F.Mask" "F.Paste")
			(net "GND")
		)
		(pad "D20" smd circle
			(at -4.750054 -19.949922)
			(size 0.4572 0.4572)
			(layers "F.Cu" "F.Mask" "F.Paste")
			(net "P5E_PEX1_STN6_RX_DP<99>")
		)
		(pad "D21" smd circle
			(at -3.800094 -19.949922)
			(size 0.4572 0.4572)
			(layers "F.Cu" "F.Mask" "F.Paste")
			(net "GND")
		)
		(pad "D22" smd circle
			(at -2.84988 -19.949922)
			(size 0.4572 0.4572)
			(layers "F.Cu" "F.Mask" "F.Paste")
			(net "P5E_PEX1_STN6_RX_DP<97>")
		)
		(pad "D23" smd circle
			(at -1.89992 -19.949922)
			(size 0.4572 0.4572)
			(layers "F.Cu" "F.Mask" "F.Paste")
			(net "GND")
		)
		(pad "D24" smd circle
			(at -0.94996 -19.949922)
			(size 0.4572 0.4572)
			(layers "F.Cu" "F.Mask" "F.Paste")
			(net "P5E_PEX1_STN5_RX_DP<80>")
		)
		(pad "D25" smd circle
			(at 0 -19.949922)
			(size 0.4572 0.4572)
			(layers "F.Cu" "F.Mask" "F.Paste")
			(net "GND")
		)
		(pad "D26" smd circle
			(at 0.94996 -19.949922)
			(size 0.4572 0.4572)
			(layers "F.Cu" "F.Mask" "F.Paste")
			(net "P5E_PEX1_STN5_RX_DP<82>")
		)
		(pad "D27" smd circle
			(at 1.89992 -19.949922)
			(size 0.4572 0.4572)
			(layers "F.Cu" "F.Mask" "F.Paste")
			(net "GND")
		)
		(pad "D28" smd circle
			(at 2.84988 -19.949922)
			(size 0.4572 0.4572)
			(layers "F.Cu" "F.Mask" "F.Paste")
			(net "P5E_PEX1_STN5_RX_DP<84>")
		)
		(pad "D29" smd circle
			(at 3.800094 -19.949922)
			(size 0.4572 0.4572)
			(layers "F.Cu" "F.Mask" "F.Paste")
			(net "GND")
		)
		(pad "D30" smd circle
			(at 4.750054 -19.949922)
			(size 0.4572 0.4572)
			(layers "F.Cu" "F.Mask" "F.Paste")
			(net "P5E_PEX1_STN5_RX_DP<86>")
		)
		(pad "D31" smd circle
			(at 5.700014 -19.949922)
			(size 0.4572 0.4572)
			(layers "F.Cu" "F.Mask" "F.Paste")
			(net "GND")
		)
		(pad "D32" smd circle
			(at 6.649974 -19.949922)
			(size 0.4572 0.4572)
			(layers "F.Cu" "F.Mask" "F.Paste")
			(net "P5E_PEX1_STN5_RX_DP<88>")
		)
		(pad "D33" smd circle
			(at 7.599934 -19.949922)
			(size 0.4572 0.4572)
			(layers "F.Cu" "F.Mask" "F.Paste")
			(net "GND")
		)
		(pad "D34" smd circle
			(at 8.549894 -19.949922)
			(size 0.4572 0.4572)
			(layers "F.Cu" "F.Mask" "F.Paste")
			(net "P5E_PEX1_STN5_RX_DP<90>")
		)
		(pad "D35" smd circle
			(at 9.500108 -19.949922)
			(size 0.4572 0.4572)
			(layers "F.Cu" "F.Mask" "F.Paste")
			(net "GND")
		)
		(pad "D36" smd circle
			(at 10.450068 -19.949922)
			(size 0.4572 0.4572)
			(layers "F.Cu" "F.Mask" "F.Paste")
			(net "P5E_PEX1_STN5_RX_DP<92>")
		)
		(pad "D37" smd circle
			(at 11.400028 -19.949922)
			(size 0.4572 0.4572)
			(layers "F.Cu" "F.Mask" "F.Paste")
			(net "GND")
		)
		(pad "D38" smd circle
			(at 12.349988 -19.949922)
			(size 0.4572 0.4572)
			(layers "F.Cu" "F.Mask" "F.Paste")
			(net "P5E_PEX1_STN5_RX_DP<94>")
		)
		(pad "D39" smd circle
			(at 13.299948 -19.949922)
			(size 0.4572 0.4572)
			(layers "F.Cu" "F.Mask" "F.Paste")
			(net "GND")
		)
		(pad "D40" smd circle
			(at 14.249908 -19.949922)
			(size 0.4572 0.4572)
			(layers "F.Cu" "F.Mask" "F.Paste")
			(net "P5E_PEX1_STN4_RX_DP<79>")
		)
		(pad "D41" smd circle
			(at 15.200122 -19.949922)
			(size 0.4572 0.4572)
			(layers "F.Cu" "F.Mask" "F.Paste")
			(net "GND")
		)
		(pad "D42" smd circle
			(at 16.150082 -19.949922)
			(size 0.4572 0.4572)
			(layers "F.Cu" "F.Mask" "F.Paste")
			(net "P5E_PEX1_STN4_RX_DP<77>")
		)
		(pad "D43" smd circle
			(at 17.100042 -19.949922)
			(size 0.4572 0.4572)
			(layers "F.Cu" "F.Mask" "F.Paste")
			(net "GND")
		)
		(pad "D44" smd circle
			(at 18.050002 -19.949922)
			(size 0.4572 0.4572)
			(layers "F.Cu" "F.Mask" "F.Paste")
			(net "P5E_PEX1_STN4_RX_DP<75>")
		)
		(pad "D45" smd circle
			(at 18.999962 -19.949922)
			(size 0.4572 0.4572)
			(layers "F.Cu" "F.Mask" "F.Paste")
			(net "GND")
		)
		(pad "D46" smd circle
			(at 19.949922 -19.949922)
			(size 0.4572 0.4572)
			(layers "F.Cu" "F.Mask" "F.Paste")
			(net "P5E_PEX1_STN4_RX_DP<73>")
		)
		(pad "D47" smd circle
			(at 20.899882 -19.949922)
			(size 0.4572 0.4572)
			(layers "F.Cu" "F.Mask" "F.Paste")
			(net "GND")
		)
		(pad "D48" smd circle
			(at 21.850096 -19.949922)
			(size 0.4572 0.4572)
			(layers "F.Cu" "F.Mask" "F.Paste")
			(net "GND")
		)
		(pad "D49" smd circle
			(at 22.800056 -19.949922)
			(size 0.4572 0.4572)
			(layers "F.Cu" "F.Mask" "F.Paste")
			(net "GND")
		)
		(pad "E1" smd circle
			(at -22.800056 -18.999962)
			(size 0.4572 0.4572)
			(layers "F.Cu" "F.Mask" "F.Paste")
			(net "P5E_PEX1_STN7_TX_DN<122>")
		)
		(pad "E2" smd circle
			(at -21.850096 -18.999962)
			(size 0.4572 0.4572)
			(layers "F.Cu" "F.Mask" "F.Paste")
			(net "P5E_PEX1_STN7_TX_DP<122>")
		)
		(pad "E3" smd circle
			(at -20.899882 -18.999962)
			(size 0.4572 0.4572)
			(layers "F.Cu" "F.Mask" "F.Paste")
			(net "GND")
		)
		(pad "E4" smd circle
			(at -19.949922 -18.999962)
			(size 0.4572 0.4572)
			(layers "F.Cu" "F.Mask" "F.Paste")
			(net "GND")
		)
		(pad "E5" smd circle
			(at -18.999962 -18.999962)
			(size 0.4572 0.4572)
			(layers "F.Cu" "F.Mask" "F.Paste")
			(net "GND")
		)
		(pad "E6" smd circle
			(at -18.050002 -18.999962)
			(size 0.4572 0.4572)
			(layers "F.Cu" "F.Mask" "F.Paste")
			(net "GND")
		)
		(pad "E7" smd circle
			(at -17.100042 -18.999962)
			(size 0.4572 0.4572)
			(layers "F.Cu" "F.Mask" "F.Paste")
			(net "GND")
		)
		(pad "E8" smd circle
			(at -16.150082 -18.999962)
			(size 0.4572 0.4572)
			(layers "F.Cu" "F.Mask" "F.Paste")
			(net "GND")
		)
		(pad "E9" smd circle
			(at -15.200122 -18.999962)
			(size 0.4572 0.4572)
			(layers "F.Cu" "F.Mask" "F.Paste")
			(net "GND")
		)
		(pad "E10" smd circle
			(at -14.249908 -18.999962)
			(size 0.4572 0.4572)
			(layers "F.Cu" "F.Mask" "F.Paste")
			(net "GND")
		)
		(pad "E11" smd circle
			(at -13.299948 -18.999962)
			(size 0.4572 0.4572)
			(layers "F.Cu" "F.Mask" "F.Paste")
			(net "GND")
		)
		(pad "E12" smd circle
			(at -12.349988 -18.999962)
			(size 0.4572 0.4572)
			(layers "F.Cu" "F.Mask" "F.Paste")
			(net "GND")
		)
		(pad "E13" smd circle
			(at -11.400028 -18.999962)
			(size 0.4572 0.4572)
			(layers "F.Cu" "F.Mask" "F.Paste")
			(net "GND")
		)
		(pad "E14" smd circle
			(at -10.450068 -18.999962)
			(size 0.4572 0.4572)
			(layers "F.Cu" "F.Mask" "F.Paste")
			(net "GND")
		)
		(pad "E15" smd circle
			(at -9.500108 -18.999962)
			(size 0.4572 0.4572)
			(layers "F.Cu" "F.Mask" "F.Paste")
			(net "GND")
		)
		(pad "E16" smd circle
			(at -8.549894 -18.999962)
			(size 0.4572 0.4572)
			(layers "F.Cu" "F.Mask" "F.Paste")
			(net "GND")
		)
		(pad "E17" smd circle
			(at -7.599934 -18.999962)
			(size 0.4572 0.4572)
			(layers "F.Cu" "F.Mask" "F.Paste")
			(net "GND")
		)
		(pad "E18" smd circle
			(at -6.649974 -18.999962)
			(size 0.4572 0.4572)
			(layers "F.Cu" "F.Mask" "F.Paste")
			(net "GND")
		)
		(pad "E19" smd circle
			(at -5.700014 -18.999962)
			(size 0.4572 0.4572)
			(layers "F.Cu" "F.Mask" "F.Paste")
			(net "GND")
		)
		(pad "E20" smd circle
			(at -4.750054 -18.999962)
			(size 0.4572 0.4572)
			(layers "F.Cu" "F.Mask" "F.Paste")
			(net "GND")
		)
		(pad "E21" smd circle
			(at -3.800094 -18.999962)
			(size 0.4572 0.4572)
			(layers "F.Cu" "F.Mask" "F.Paste")
			(net "GND")
		)
		(pad "E22" smd circle
			(at -2.84988 -18.999962)
			(size 0.4572 0.4572)
			(layers "F.Cu" "F.Mask" "F.Paste")
			(net "GND")
		)
		(pad "E23" smd circle
			(at -1.89992 -18.999962)
			(size 0.4572 0.4572)
			(layers "F.Cu" "F.Mask" "F.Paste")
			(net "GND")
		)
		(pad "E24" smd circle
			(at -0.94996 -18.999962)
			(size 0.4572 0.4572)
			(layers "F.Cu" "F.Mask" "F.Paste")
			(net "GND")
		)
		(pad "E25" smd circle
			(at 0 -18.999962)
			(size 0.4572 0.4572)
			(layers "F.Cu" "F.Mask" "F.Paste")
			(net "GND")
		)
		(pad "E26" smd circle
			(at 0.94996 -18.999962)
			(size 0.4572 0.4572)
			(layers "F.Cu" "F.Mask" "F.Paste")
			(net "GND")
		)
		(pad "E27" smd circle
			(at 1.89992 -18.999962)
			(size 0.4572 0.4572)
			(layers "F.Cu" "F.Mask" "F.Paste")
			(net "GND")
		)
		(pad "E28" smd circle
			(at 2.84988 -18.999962)
			(size 0.4572 0.4572)
			(layers "F.Cu" "F.Mask" "F.Paste")
			(net "GND")
		)
		(pad "E29" smd circle
			(at 3.800094 -18.999962)
			(size 0.4572 0.4572)
			(layers "F.Cu" "F.Mask" "F.Paste")
			(net "GND")
		)
		(pad "E30" smd circle
			(at 4.750054 -18.999962)
			(size 0.4572 0.4572)
			(layers "F.Cu" "F.Mask" "F.Paste")
			(net "GND")
		)
		(pad "E31" smd circle
			(at 5.700014 -18.999962)
			(size 0.4572 0.4572)
			(layers "F.Cu" "F.Mask" "F.Paste")
			(net "GND")
		)
		(pad "E32" smd circle
			(at 6.649974 -18.999962)
			(size 0.4572 0.4572)
			(layers "F.Cu" "F.Mask" "F.Paste")
			(net "GND")
		)
		(pad "E33" smd circle
			(at 7.599934 -18.999962)
			(size 0.4572 0.4572)
			(layers "F.Cu" "F.Mask" "F.Paste")
			(net "GND")
		)
		(pad "E34" smd circle
			(at 8.549894 -18.999962)
			(size 0.4572 0.4572)
			(layers "F.Cu" "F.Mask" "F.Paste")
			(net "GND")
		)
		(pad "E35" smd circle
			(at 9.500108 -18.999962)
			(size 0.4572 0.4572)
			(layers "F.Cu" "F.Mask" "F.Paste")
			(net "GND")
		)
		(pad "E36" smd circle
			(at 10.450068 -18.999962)
			(size 0.4572 0.4572)
			(layers "F.Cu" "F.Mask" "F.Paste")
			(net "GND")
		)
		(pad "E37" smd circle
			(at 11.400028 -18.999962)
			(size 0.4572 0.4572)
			(layers "F.Cu" "F.Mask" "F.Paste")
			(net "GND")
		)
		(pad "E38" smd circle
			(at 12.349988 -18.999962)
			(size 0.4572 0.4572)
			(layers "F.Cu" "F.Mask" "F.Paste")
			(net "GND")
		)
		(pad "E39" smd circle
			(at 13.299948 -18.999962)
			(size 0.4572 0.4572)
			(layers "F.Cu" "F.Mask" "F.Paste")
			(net "GND")
		)
		(pad "E40" smd circle
			(at 14.249908 -18.999962)
			(size 0.4572 0.4572)
			(layers "F.Cu" "F.Mask" "F.Paste")
			(net "GND")
		)
	)
)
